#ISCELL
  pure_quanta quanta_title_block_c *
  *
#ISCELL
  standard offpage *
  page122_i1
#CELL
  pure_quanta bc847bpn *
  page122_i10
#ISCELL
  logical_power universal_power *
  page122_i11
#CELL
  pure_quanta bc847bpn *
  page122_i12
#ISCELL
  logical_power universal_power *
  page122_i13
#ISCELL
  logical_power universal_power *
  page122_i14
#CELL
  pure_quanta q_res *
  page122_i15
#CELL
  pure_quanta q_res *
  page122_i16
#CELL
  pure_quanta bc847bpn *
  page122_i17
#CELL
  pure_quanta q_res *
  page122_i18
#ISCELL
  standard offpage *
  page122_i19
#ISCELL
  standard offpage *
  page122_i2
#CELL
  pure_quanta q_res *
  page122_i20
#CELL
  pure_quanta q_res *
  page122_i21
#CELL
  pure_quanta bc847bpn *
  page122_i22
#ISCELL
  logical_power universal_gnd *
  page122_i23
#CELL
  pure_quanta q_res *
  page122_i24
#ISCELL
  logical_power universal_power *
  page122_i25
#ISCELL
  logical_power universal_gnd *
  page122_i26
#CELL
  pure_quanta q_res *
  page122_i27
#ISCELL
  logical_power universal_power *
  page122_i28
#CELL
  pure_quanta q_res *
  page122_i29
#ISCELL
  standard offpage *
  page122_i3
#ISCELL
  logical_power universal_power *
  page122_i30
#CELL
  pure_quanta q_res *
  page122_i31
#ISCELL
  standard offpage *
  page122_i32
#CELL
  pure_quanta q_res *
  page122_i33
#CELL
  pure_quanta q_res *
  page122_i34
#ISCELL
  standard offpage *
  page122_i35
#ISCELL
  standard offpage *
  page122_i36
#CELL
  pure_quanta q_res *
  page122_i37
#ISCELL
  logical_power universal_power *
  page122_i38
#ISCELL
  standard offpage *
  page122_i4
#CELL
  pure_quanta q_res *
  page122_i5
#CELL
  pure_quanta q_res *
  page122_i6
#ISCELL
  logical_power universal_power *
  page122_i7
#CELL
  pure_quanta q_res *
  page122_i8
#CELL
  pure_quanta q_res *
  page122_i9
